(kicad_pcb
	(version 20241229)
	(generator "pcbnew")
	(generator_version "9.0")
	(general
		(thickness 1.6)
		(legacy_teardrops no)
	)
	(paper "A4")
	(title_block
		(title "GMSL Deserializer")
		(date "2025-10-09")
		(rev "1.0.4")
		(company "Antmicro Ltd")
		(comment 1 "www.antmicro.com")
		(comment 9 "footprints 67-72 of 235")
	)
	(layers
		(0 "F.Cu" signal)
		(4 "In1.Cu" power)
		(6 "In2.Cu" power)
		(2 "B.Cu" signal)
		(9 "F.Adhes" user "F.Adhesive")
		(11 "B.Adhes" user "B.Adhesive")
		(13 "F.Paste" user)
		(15 "B.Paste" user)
		(5 "F.SilkS" user "F.Silkscreen")
		(7 "B.SilkS" user "B.Silkscreen")
		(1 "F.Mask" user)
		(3 "B.Mask" user)
		(17 "Dwgs.User" user "User.Drawings")
		(19 "Cmts.User" user "User.Comments")
		(21 "Eco1.User" user "User.Eco1")
		(23 "Eco2.User" user "User.Eco2")
		(25 "Edge.Cuts" user)
		(27 "Margin" user)
		(31 "F.CrtYd" user "F.Courtyard")
		(29 "B.CrtYd" user "B.Courtyard")
		(35 "F.Fab" user)
		(33 "B.Fab" user)
	)
	(footprint "antmicro-footprints:C_0402_1005Metric"
		(layer "F.Cu")
		(at 149.733 71.6788 90)
		(descr "Capacitor SMD 0402")
		(tags "capacitor SMD 0402")
		(property "Reference" "C56"
			(at 1.0668 0.381 90)
			(layer "F.SilkS")
			(effects
				(font
					(size 0.7 0.7)
					(thickness 0.15)
				)
				(justify left bottom)
			)
		)
		(property "Value" "C_33p_0402"
			(at -1.022927 2.155213 90)
			(layer "F.Fab")
			(effects
				(font
					(size 0.7 0.7)
					(thickness 0.15)
				)
				(justify left bottom)
			)
		)
		(property "Datasheet" "https://spicat.kyocera-avx.com/product/mlcc/chartview/04025A330FAT2A/"
			(at 0 0 90)
			(layer "F.Fab")
			(hide yes)
			(effects
				(font
					(size 1.27 1.27)
					(thickness 0.15)
				)
			)
		)
		(property "Description" "SMD Multilayer Ceramic Capacitor, 33 pF, 50 V, 0402 [1005 Metric], ± 5%, C0G / NP0, MC"
			(at 0 0 90)
			(layer "F.Fab")
			(hide yes)
			(effects
				(font
					(size 1.27 1.27)
					(thickness 0.15)
				)
			)
		)
		(property "Author" "Antmicro"
			(at 221.4118 -78.0542 0)
			(layer "F.Fab")
			(hide yes)
			(effects
				(font
					(size 1 1)
					(thickness 0.15)
				)
			)
		)
		(property "Dielectric" ""
			(at 221.4118 -78.0542 0)
			(layer "F.Fab")
			(hide yes)
			(effects
				(font
					(size 1 1)
					(thickness 0.15)
				)
			)
		)
		(property "License" "Apache-2.0"
			(at 221.4118 -78.0542 0)
			(layer "F.Fab")
			(hide yes)
			(effects
				(font
					(size 1 1)
					(thickness 0.15)
				)
			)
		)
		(property "MPN" "04025A330FAT2A"
			(at 221.4118 -78.0542 0)
			(layer "F.Fab")
			(hide yes)
			(effects
				(font
					(size 1 1)
					(thickness 0.15)
				)
			)
		)
		(property "Manufacturer" "KYOCERA AVX"
			(at 221.4118 -78.0542 0)
			(layer "F.Fab")
			(hide yes)
			(effects
				(font
					(size 1 1)
					(thickness 0.15)
				)
			)
		)
		(property "Val" "33p"
			(at 221.4118 -78.0542 0)
			(layer "F.Fab")
			(hide yes)
			(effects
				(font
					(size 1 1)
					(thickness 0.15)
				)
			)
		)
		(property "Voltage" ""
			(at 221.4118 -78.0542 0)
			(layer "F.Fab")
			(hide yes)
			(effects
				(font
					(size 1 1)
					(thickness 0.15)
				)
			)
		)
		(sheetname "/Deserializer/")
		(sheetfile "deserializer.kicad_sch")
		(attr smd)
		(fp_rect
			(start -0.925 -0.47)
			(end 0.925 0.47)
			(stroke
				(width 0.05)
				(type default)
			)
			(fill no)
			(layer "F.CrtYd")
		)
		(fp_line
			(start 0.504 -0.25)
			(end 0.504 0.248)
			(stroke
				(width 0.15)
				(type solid)
			)
			(layer "F.Fab")
		)
		(fp_line
			(start -0.494 -0.25)
			(end 0.504 -0.25)
			(stroke
				(width 0.15)
				(type solid)
			)
			(layer "F.Fab")
		)
		(fp_line
			(start 0.504 0.248)
			(end -0.494 0.248)
			(stroke
				(width 0.15)
				(type solid)
			)
			(layer "F.Fab")
		)
		(fp_line
			(start -0.494 0.248)
			(end -0.494 -0.25)
			(stroke
				(width 0.15)
				(type solid)
			)
			(layer "F.Fab")
		)
		(pad "1" smd roundrect
			(at -0.48 0 90)
			(size 0.59 0.64)
			(layers "F.Cu" "F.Mask" "F.Paste")
			(roundrect_rratio 0.25)
			(net 1 "GND")
			(pintype "passive")
		)
		(pad "2" smd roundrect
			(at 0.48 0 90)
			(size 0.59 0.64)
			(layers "F.Cu" "F.Mask" "F.Paste")
			(roundrect_rratio 0.25)
			(net 12 "/Deserializer/X1")
			(pintype "passive")
		)
	)
	(footprint "antmicro-footprints:R_0402_1005Metric"
		(layer "F.Cu")
		(at 184.077 54.7648 90)
		(descr "Resistor SMD 0402")
		(tags "resistor SMD 0402")
		(property "Reference" "R34"
			(at -1.293 -0.689 90)
			(layer "F.SilkS")
			(effects
				(font
					(size 0.7 0.7)
					(thickness 0.15)
				)
				(justify left bottom)
			)
		)
		(property "Value" "R_10k_0402"
			(at -1.011843 1.772047 90)
			(layer "F.Fab")
			(effects
				(font
					(size 0.7 0.7)
					(thickness 0.15)
				)
				(justify left bottom)
			)
		)
		(property "Datasheet" "https://www.bourns.com/docs/product-datasheets/cr.pdf"
			(at 0 0 90)
			(layer "F.Fab")
			(hide yes)
			(effects
				(font
					(size 1.27 1.27)
					(thickness 0.15)
				)
			)
		)
		(property "Description" "SMD Chip Resistor, 10 kohm, ± 1%, 62.5 mW, 0402 [1005 Metric], Thick Film, General Purpose"
			(at 0 0 90)
			(layer "F.Fab")
			(hide yes)
			(effects
				(font
					(size 1.27 1.27)
					(thickness 0.15)
				)
			)
		)
		(property "Author" "Antmicro"
			(at 238.8418 -129.3122 0)
			(layer "F.Fab")
			(hide yes)
			(effects
				(font
					(size 1 1)
					(thickness 0.15)
				)
			)
		)
		(property "License" "Apache-2.0"
			(at 238.8418 -129.3122 0)
			(layer "F.Fab")
			(hide yes)
			(effects
				(font
					(size 1 1)
					(thickness 0.15)
				)
			)
		)
		(property "MPN" "CR0402-FX-1002GLF"
			(at 238.8418 -129.3122 0)
			(layer "F.Fab")
			(hide yes)
			(effects
				(font
					(size 1 1)
					(thickness 0.15)
				)
			)
		)
		(property "Manufacturer" "Bourns"
			(at 238.8418 -129.3122 0)
			(layer "F.Fab")
			(hide yes)
			(effects
				(font
					(size 1 1)
					(thickness 0.15)
				)
			)
		)
		(property "Tolerance" "1%"
			(at 238.8418 -129.3122 0)
			(layer "F.Fab")
			(hide yes)
			(effects
				(font
					(size 1 1)
					(thickness 0.15)
				)
			)
		)
		(property "Val" "10k"
			(at 238.8418 -129.3122 0)
			(layer "F.Fab")
			(hide yes)
			(effects
				(font
					(size 1 1)
					(thickness 0.15)
				)
			)
		)
		(sheetname "/Power/")
		(sheetfile "power.kicad_sch")
		(attr smd exclude_from_pos_files exclude_from_bom dnp)
		(fp_rect
			(start -0.925 -0.47)
			(end 0.925 0.47)
			(stroke
				(width 0.05)
				(type default)
			)
			(fill no)
			(layer "F.CrtYd")
		)
		(fp_rect
			(start -0.5 -0.25)
			(end 0.5 0.25)
			(stroke
				(width 0.15)
				(type solid)
			)
			(fill no)
			(layer "F.Fab")
		)
		(pad "1" smd roundrect
			(at -0.48 0 90)
			(size 0.59 0.64)
			(layers "F.Cu" "F.Mask" "F.Paste")
			(roundrect_rratio 0.25)
			(net 1 "GND")
			(pintype "passive")
		)
		(pad "2" smd roundrect
			(at 0.48 0 90)
			(size 0.59 0.64)
			(layers "F.Cu" "F.Mask" "F.Paste")
			(roundrect_rratio 0.25)
			(net 63 "/Power/FFC_5V_EN")
			(pintype "passive")
		)
	)
	(footprint "antmicro-footprints:R_0402_1005Metric"
		(layer "F.Cu")
		(at 119.149 85.344 180)
		(descr "Resistor SMD 0402")
		(tags "resistor SMD 0402")
		(property "Reference" "R31"
			(at 1.039 -0.508 0)
			(layer "F.SilkS")
			(effects
				(font
					(size 0.7 0.7)
					(thickness 0.15)
				)
				(justify right bottom)
			)
		)
		(property "Value" "R_10k_0402"
			(at -1.011843 1.772047 0)
			(layer "F.Fab")
			(effects
				(font
					(size 0.7 0.7)
					(thickness 0.15)
				)
				(justify right bottom)
			)
		)
		(property "Datasheet" "https://www.bourns.com/docs/product-datasheets/cr.pdf"
			(at 0 0 180)
			(layer "F.Fab")
			(hide yes)
			(effects
				(font
					(size 1.27 1.27)
					(thickness 0.15)
				)
			)
		)
		(property "Description" "SMD Chip Resistor, 10 kohm, ± 1%, 62.5 mW, 0402 [1005 Metric], Thick Film, General Purpose"
			(at 0 0 180)
			(layer "F.Fab")
			(hide yes)
			(effects
				(font
					(size 1.27 1.27)
					(thickness 0.15)
				)
			)
		)
		(property "Author" "Antmicro"
			(at 238.298 170.688 0)
			(layer "F.Fab")
			(hide yes)
			(effects
				(font
					(size 1 1)
					(thickness 0.15)
				)
			)
		)
		(property "License" "Apache-2.0"
			(at 238.298 170.688 0)
			(layer "F.Fab")
			(hide yes)
			(effects
				(font
					(size 1 1)
					(thickness 0.15)
				)
			)
		)
		(property "MPN" "CR0402-FX-1002GLF"
			(at 238.298 170.688 0)
			(layer "F.Fab")
			(hide yes)
			(effects
				(font
					(size 1 1)
					(thickness 0.15)
				)
			)
		)
		(property "Manufacturer" "Bourns"
			(at 238.298 170.688 0)
			(layer "F.Fab")
			(hide yes)
			(effects
				(font
					(size 1 1)
					(thickness 0.15)
				)
			)
		)
		(property "Tolerance" "1%"
			(at 238.298 170.688 0)
			(layer "F.Fab")
			(hide yes)
			(effects
				(font
					(size 1 1)
					(thickness 0.15)
				)
			)
		)
		(property "Val" "10k"
			(at 238.298 170.688 0)
			(layer "F.Fab")
			(hide yes)
			(effects
				(font
					(size 1 1)
					(thickness 0.15)
				)
			)
		)
		(sheetname "/Power/")
		(sheetfile "power.kicad_sch")
		(attr smd)
		(fp_rect
			(start -0.925 -0.47)
			(end 0.925 0.47)
			(stroke
				(width 0.05)
				(type default)
			)
			(fill no)
			(layer "F.CrtYd")
		)
		(fp_rect
			(start -0.5 -0.25)
			(end 0.5 0.25)
			(stroke
				(width 0.15)
				(type solid)
			)
			(fill no)
			(layer "F.Fab")
		)
		(pad "1" smd roundrect
			(at -0.48 0 180)
			(size 0.59 0.64)
			(layers "F.Cu" "F.Mask" "F.Paste")
			(roundrect_rratio 0.25)
			(net 68 "/Power/EN_1V2")
			(pintype "passive")
		)
		(pad "2" smd roundrect
			(at 0.48 0 180)
			(size 0.59 0.64)
			(layers "F.Cu" "F.Mask" "F.Paste")
			(roundrect_rratio 0.25)
			(net 4 "+12V")
			(pintype "passive")
		)
	)
	(footprint "antmicro-footprints:C_0402_1005Metric"
		(layer "F.Cu")
		(at 157.154 66.548 90)
		(descr "Capacitor SMD 0402")
		(tags "capacitor SMD 0402")
		(property "Reference" "C9"
			(at -1.397 -0.563 90)
			(layer "F.SilkS")
			(effects
				(font
					(size 0.7 0.7)
					(thickness 0.15)
				)
				(justify left bottom)
			)
		)
		(property "Value" "C_100n_0402"
			(at -1.022927 2.155213 90)
			(layer "F.Fab")
			(effects
				(font
					(size 0.7 0.7)
					(thickness 0.15)
				)
				(justify left bottom)
			)
		)
		(property "Datasheet" "https://www.murata.com/products/productdetail?partno=GRM155R61H104KE14%23"
			(at 0 0 90)
			(layer "F.Fab")
			(hide yes)
			(effects
				(font
					(size 1.27 1.27)
					(thickness 0.15)
				)
			)
		)
		(property "Description" "SMD Multilayer Ceramic Capacitor, 0.1 µF, 50 V, 0402 [1005 Metric], ± 10%, X5R, GRM Series"
			(at 0 0 90)
			(layer "F.Fab")
			(hide yes)
			(effects
				(font
					(size 1.27 1.27)
					(thickness 0.15)
				)
			)
		)
		(property "Author" "Antmicro"
			(at 223.702 -90.606 0)
			(layer "F.Fab")
			(hide yes)
			(effects
				(font
					(size 1 1)
					(thickness 0.15)
				)
			)
		)
		(property "Dielectric" "X5R"
			(at 223.702 -90.606 0)
			(layer "F.Fab")
			(hide yes)
			(effects
				(font
					(size 1 1)
					(thickness 0.15)
				)
			)
		)
		(property "License" "Apache-2.0"
			(at 223.702 -90.606 0)
			(layer "F.Fab")
			(hide yes)
			(effects
				(font
					(size 1 1)
					(thickness 0.15)
				)
			)
		)
		(property "MPN" "GRM155R61H104KE14D"
			(at 223.702 -90.606 0)
			(layer "F.Fab")
			(hide yes)
			(effects
				(font
					(size 1 1)
					(thickness 0.15)
				)
			)
		)
		(property "Manufacturer" "Murata"
			(at 223.702 -90.606 0)
			(layer "F.Fab")
			(hide yes)
			(effects
				(font
					(size 1 1)
					(thickness 0.15)
				)
			)
		)
		(property "Val" "100n"
			(at 223.702 -90.606 0)
			(layer "F.Fab")
			(hide yes)
			(effects
				(font
					(size 1 1)
					(thickness 0.15)
				)
			)
		)
		(property "Voltage" "50V"
			(at 223.702 -90.606 0)
			(layer "F.Fab")
			(hide yes)
			(effects
				(font
					(size 1 1)
					(thickness 0.15)
				)
			)
		)
		(sheetname "/Power/")
		(sheetfile "power.kicad_sch")
		(attr smd)
		(fp_rect
			(start -0.925 -0.47)
			(end 0.925 0.47)
			(stroke
				(width 0.05)
				(type default)
			)
			(fill no)
			(layer "F.CrtYd")
		)
		(fp_line
			(start 0.504 -0.25)
			(end 0.504 0.248)
			(stroke
				(width 0.15)
				(type solid)
			)
			(layer "F.Fab")
		)
		(fp_line
			(start -0.494 -0.25)
			(end 0.504 -0.25)
			(stroke
				(width 0.15)
				(type solid)
			)
			(layer "F.Fab")
		)
		(fp_line
			(start 0.504 0.248)
			(end -0.494 0.248)
			(stroke
				(width 0.15)
				(type solid)
			)
			(layer "F.Fab")
		)
		(fp_line
			(start -0.494 0.248)
			(end -0.494 -0.25)
			(stroke
				(width 0.15)
				(type solid)
			)
			(layer "F.Fab")
		)
		(pad "1" smd roundrect
			(at -0.48 0 90)
			(size 0.59 0.64)
			(layers "F.Cu" "F.Mask" "F.Paste")
			(roundrect_rratio 0.25)
			(net 1 "GND")
			(pintype "passive")
		)
		(pad "2" smd roundrect
			(at 0.48 0 90)
			(size 0.59 0.64)
			(layers "F.Cu" "F.Mask" "F.Paste")
			(roundrect_rratio 0.25)
			(net 4 "+12V")
			(pintype "passive")
		)
	)
	(footprint "antmicro-footprints:R_0402_1005Metric"
		(layer "F.Cu")
		(at 162.052 61.976 90)
		(descr "Resistor SMD 0402")
		(tags "resistor SMD 0402")
		(property "Reference" "R22"
			(at -1.122484 1.27 90)
			(layer "F.SilkS")
			(effects
				(font
					(size 0.7 0.7)
					(thickness 0.15)
				)
				(justify left bottom)
			)
		)
		(property "Value" "R_5k1_0402"
			(at -1.011843 1.772047 90)
			(layer "F.Fab")
			(effects
				(font
					(size 0.7 0.7)
					(thickness 0.15)
				)
				(justify left bottom)
			)
		)
		(property "Datasheet" "https://www.bourns.com/docs/product-datasheets/cr.pdf"
			(at 0 0 90)
			(layer "F.Fab")
			(hide yes)
			(effects
				(font
					(size 1.27 1.27)
					(thickness 0.15)
				)
			)
		)
		(property "Description" "SMD Chip Resistor, 5.1 kohm, ± 1%, 63 mW, 0402 [1005 Metric], Thick Film, General Purpose"
			(at 0 0 90)
			(layer "F.Fab")
			(hide yes)
			(effects
				(font
					(size 1.27 1.27)
					(thickness 0.15)
				)
			)
		)
		(property "Author" "Antmicro"
			(at 224.028 -100.076 0)
			(layer "F.Fab")
			(hide yes)
			(effects
				(font
					(size 1 1)
					(thickness 0.15)
				)
			)
		)
		(property "License" "Apache-2.0"
			(at 224.028 -100.076 0)
			(layer "F.Fab")
			(hide yes)
			(effects
				(font
					(size 1 1)
					(thickness 0.15)
				)
			)
		)
		(property "MPN" "CR0402-FX-5101GLF"
			(at 224.028 -100.076 0)
			(layer "F.Fab")
			(hide yes)
			(effects
				(font
					(size 1 1)
					(thickness 0.15)
				)
			)
		)
		(property "Manufacturer" "Bourns"
			(at 224.028 -100.076 0)
			(layer "F.Fab")
			(hide yes)
			(effects
				(font
					(size 1 1)
					(thickness 0.15)
				)
			)
		)
		(property "Tolerance" "1%"
			(at 224.028 -100.076 0)
			(layer "F.Fab")
			(hide yes)
			(effects
				(font
					(size 1 1)
					(thickness 0.15)
				)
			)
		)
		(property "Val" "5k1"
			(at 224.028 -100.076 0)
			(layer "F.Fab")
			(hide yes)
			(effects
				(font
					(size 1 1)
					(thickness 0.15)
				)
			)
		)
		(sheetname "/Power/")
		(sheetfile "power.kicad_sch")
		(attr smd)
		(fp_rect
			(start -0.925 -0.47)
			(end 0.925 0.47)
			(stroke
				(width 0.05)
				(type default)
			)
			(fill no)
			(layer "F.CrtYd")
		)
		(fp_rect
			(start -0.5 -0.25)
			(end 0.5 0.25)
			(stroke
				(width 0.15)
				(type solid)
			)
			(fill no)
			(layer "F.Fab")
		)
		(pad "1" smd roundrect
			(at -0.48 0 90)
			(size 0.59 0.64)
			(layers "F.Cu" "F.Mask" "F.Paste")
			(roundrect_rratio 0.25)
			(net 4 "+12V")
			(pintype "passive")
		)
		(pad "2" smd roundrect
			(at 0.48 0 90)
			(size 0.59 0.64)
			(layers "F.Cu" "F.Mask" "F.Paste")
			(roundrect_rratio 0.25)
			(net 54 "Net-(L4-Pad2)")
			(pintype "passive")
		)
	)
	(footprint "antmicro-footprints:R_0402_1005Metric"
		(layer "F.Cu")
		(at 178.482 64.108 90)
		(descr "Resistor SMD 0402")
		(tags "resistor SMD 0402")
		(property "Reference" "R63"
			(at -10.568 0.588 90)
			(layer "F.SilkS")
			(effects
				(font
					(size 0.7 0.7)
					(thickness 0.15)
				)
				(justify left bottom)
			)
		)
		(property "Value" "R_2k2_0402"
			(at -1.011843 1.772047 90)
			(layer "F.Fab")
			(effects
				(font
					(size 0.7 0.7)
					(thickness 0.15)
				)
				(justify left bottom)
			)
		)
		(property "Datasheet" "https://www.bourns.com/docs/product-datasheets/cr.pdf"
			(at 0 0 90)
			(layer "F.Fab")
			(hide yes)
			(effects
				(font
					(size 1.27 1.27)
					(thickness 0.15)
				)
			)
		)
		(property "Description" "SMD Chip Resistor, 2.2 kohm, ± 1%, 62.5 mW, 0402 [1005 Metric], Thick Film, General Purpose"
			(at 0 0 90)
			(layer "F.Fab")
			(hide yes)
			(effects
				(font
					(size 1.27 1.27)
					(thickness 0.15)
				)
			)
		)
		(property "Author" "Antmicro"
			(at 242.59 -114.374 0)
			(layer "F.Fab")
			(hide yes)
			(effects
				(font
					(size 1 1)
					(thickness 0.15)
				)
			)
		)
		(property "License" "Apache-2.0"
			(at 242.59 -114.374 0)
			(layer "F.Fab")
			(hide yes)
			(effects
				(font
					(size 1 1)
					(thickness 0.15)
				)
			)
		)
		(property "MPN" "CR0402-FX-2201GLF"
			(at 242.59 -114.374 0)
			(layer "F.Fab")
			(hide yes)
			(effects
				(font
					(size 1 1)
					(thickness 0.15)
				)
			)
		)
		(property "Manufacturer" "Bourns"
			(at 242.59 -114.374 0)
			(layer "F.Fab")
			(hide yes)
			(effects
				(font
					(size 1 1)
					(thickness 0.15)
				)
			)
		)
		(property "Tolerance" "1%"
			(at 242.59 -114.374 0)
			(layer "F.Fab")
			(hide yes)
			(effects
				(font
					(size 1 1)
					(thickness 0.15)
				)
			)
		)
		(property "Val" "2k2"
			(at 242.59 -114.374 0)
			(layer "F.Fab")
			(hide yes)
			(effects
				(font
					(size 1 1)
					(thickness 0.15)
				)
			)
		)
		(sheetname "/Connectors/")
		(sheetfile "connectors.kicad_sch")
		(attr smd exclude_from_pos_files exclude_from_bom dnp)
		(fp_rect
			(start -0.925 -0.47)
			(end 0.925 0.47)
			(stroke
				(width 0.05)
				(type default)
			)
			(fill no)
			(layer "F.CrtYd")
		)
		(fp_rect
			(start -0.5 -0.25)
			(end 0.5 0.25)
			(stroke
				(width 0.15)
				(type solid)
			)
			(fill no)
			(layer "F.Fab")
		)
		(pad "1" smd roundrect
			(at -0.48 0 90)
			(size 0.59 0.64)
			(layers "F.Cu" "F.Mask" "F.Paste")
			(roundrect_rratio 0.25)
			(net 44 "/Connectors/SDA_CAM")
			(pintype "passive")
		)
		(pad "2" smd roundrect
			(at 0.48 0 90)
			(size 0.59 0.64)
			(layers "F.Cu" "F.Mask" "F.Paste")
			(roundrect_rratio 0.25)
			(net 50 "/Connectors/FFC_3V3")
			(pintype "passive")
		)
	)
)
